# S9S_MB_2U (Grand Teton) — schematic netlist excerpt (pin names and nets, part order shuffled) for the footprints in the layout excerpt that follows; sources: Cadence DE-HDL packaged netlist, KiCad conversion of 03242023_DA0F0TMBIJ0_F0T_Motherboard_J_brd_V01_OCP.brd

R2390  Q_RES  0 5% CHIP  pkg 0402LF  page 274 : A = SMB_VR_3V3AUX_SCL_R2 ; B = SMB_CLK_PVCCINFAON_CPU0
U2_BP  TP  NA  pkg TP_BOM ONLY  page 312 : TP = NC
PC181  Q_CAP  100NF 50V 10% X7R  pkg C0402  page 276 : A = PVCCFA_EHV_CPU0 ; B = GND

(kicad_pcb
	(version 20260206)
	(generator "pcbnew")
	(generator_version "10.0")
	(general
		(thickness 1.6)
		(legacy_teardrops no)
	)
	(paper "A4")
	(title_block
		(title "03242023_DA0F0TMBIJ0_F0T_Motherboard_J_brd_V01_OCP.brd")
		(comment 1 "Grand Teton / footprints 2638-2640 of 6105")
	)
	(layers
		(0 "F.Cu" signal "TOP")
		(4 "In1.Cu" signal "GND")
		(6 "In2.Cu" signal "IN1")
		(8 "In3.Cu" signal "GND1")
		(10 "In4.Cu" signal "IN2")
		(12 "In5.Cu" signal "GND2")
		(14 "In6.Cu" signal "IN3")
		(16 "In7.Cu" signal "GND3")
		(18 "In8.Cu" signal "VCC")
		(20 "In9.Cu" signal "VCC1")
		(22 "In10.Cu" signal "GND4")
		(24 "In11.Cu" signal "IN4")
		(26 "In12.Cu" signal "GND5")
		(28 "In13.Cu" signal "IN5")
		(30 "In14.Cu" signal "GND6")
		(32 "In15.Cu" signal "IN6")
		(34 "In16.Cu" signal "GND7")
		(2 "B.Cu" signal "BOTTOM")
		(9 "F.Adhes" user "F.Adhesive")
		(11 "B.Adhes" user "B.Adhesive")
		(13 "F.Paste" user "Package Geometry/Pastemask Top")
		(15 "B.Paste" user "Package Geometry/Pastemask Bottom")
		(5 "F.SilkS" user "Ref Des/Silkscreen Top")
		(7 "B.SilkS" user "Ref Des/Silkscreen Bottom")
		(1 "F.Mask" user "Board Geometry/Soldermask Top")
		(3 "B.Mask" user "Board Geometry/Soldermask Bottom")
		(17 "Dwgs.User" user "User.Drawings")
		(19 "Cmts.User" user "User.Comments")
		(21 "Eco1.User" user "User.Eco1")
		(23 "Eco2.User" user "User.Eco2")
		(25 "Edge.Cuts" user "Board Geometry/Outline")
		(27 "Margin" user)
		(31 "F.CrtYd" user "Package Geometry/Place Bound Top")
		(29 "B.CrtYd" user "Package Geometry/Place Bound Bottom")
		(35 "F.Fab" user "Ref Des/Assembly Top")
		(33 "B.Fab" user "Ref Des/Assembly Bottom")
	)
	(footprint ""
		(layer "F.Cu")
		(at 498.58549 -470.89187)
		(property "Reference" "U2_BP"
			(at -1.6764 -1.07823 0)
			(unlocked yes)
			(layer "F.SilkS")
			(effects
				(font
					(size 0.7874 0.5842)
					(thickness 0.1524)
				)
				(justify left)
			)
		)
		(property "Value" ""
			(at 0 0 0)
			(layer "F.Fab")
			(effects
				(font
					(size 1.27 1.27)
				)
			)
		)
		(duplicate_pad_numbers_are_jumpers no)
		(pad "1" smd circle
			(at 0 0)
			(size 0.762 0.762)
			(layers "F.Cu" "F.Mask" "F.Paste")
			(net "Net_8484")
		)
	)
	(footprint ""
		(layer "F.Cu")
		(at 409.65628 -149.037548)
		(property "Reference" "PC181"
			(at 0 0 0)
			(layer "F.SilkS")
			(hide yes)
			(effects
				(font
					(size 1.27 1.27)
				)
			)
		)
		(property "Value" ""
			(at 0 0 0)
			(layer "F.Fab")
			(effects
				(font
					(size 1.27 1.27)
				)
			)
		)
		(duplicate_pad_numbers_are_jumpers no)
		(fp_line
			(start -0.7874 -0.4064)
			(end 0.7874 -0.4064)
			(stroke
				(width 0.1524)
				(type default)
			)
			(layer "F.SilkS")
		)
		(fp_line
			(start -0.7874 0.4064)
			(end -0.7874 -0.4064)
			(stroke
				(width 0.1524)
				(type default)
			)
			(layer "F.SilkS")
		)
		(fp_line
			(start 0.7874 -0.4064)
			(end 0.7874 0.4064)
			(stroke
				(width 0.1524)
				(type default)
			)
			(layer "F.SilkS")
		)
		(fp_line
			(start 0.7874 0.4064)
			(end -0.7874 0.4064)
			(stroke
				(width 0.1524)
				(type default)
			)
			(layer "F.SilkS")
		)
		(fp_line
			(start -0.67945 -0.305054)
			(end -0.12065 -0.305054)
			(stroke
				(width 0.1)
				(type default)
			)
			(layer "F.Fab")
		)
		(fp_line
			(start -0.67945 0.3048)
			(end -0.67945 -0.305054)
			(stroke
				(width 0.1)
				(type default)
			)
			(layer "F.Fab")
		)
		(fp_line
			(start -0.12065 -0.305054)
			(end -0.12065 -0.2794)
			(stroke
				(width 0.1)
				(type default)
			)
			(layer "F.Fab")
		)
		(fp_line
			(start -0.12065 -0.2794)
			(end 0.12065 -0.2794)
			(stroke
				(width 0.1)
				(type default)
			)
			(layer "F.Fab")
		)
		(fp_line
			(start -0.12065 0.2794)
			(end -0.12065 0.3048)
			(stroke
				(width 0.1)
				(type default)
			)
			(layer "F.Fab")
		)
		(fp_line
			(start -0.12065 0.3048)
			(end -0.67945 0.3048)
			(stroke
				(width 0.1)
				(type default)
			)
			(layer "F.Fab")
		)
		(fp_line
			(start 0.120396 0.2794)
			(end -0.12065 0.2794)
			(stroke
				(width 0.1)
				(type default)
			)
			(layer "F.Fab")
		)
		(fp_line
			(start 0.120396 0.3048)
			(end 0.120396 0.2794)
			(stroke
				(width 0.1)
				(type default)
			)
			(layer "F.Fab")
		)
		(fp_line
			(start 0.12065 -0.3048)
			(end 0.67945 -0.3048)
			(stroke
				(width 0.1)
				(type default)
			)
			(layer "F.Fab")
		)
		(fp_line
			(start 0.12065 -0.2794)
			(end 0.12065 -0.3048)
			(stroke
				(width 0.1)
				(type default)
			)
			(layer "F.Fab")
		)
		(fp_line
			(start 0.67945 -0.3048)
			(end 0.67945 0.3048)
			(stroke
				(width 0.1)
				(type default)
			)
			(layer "F.Fab")
		)
		(fp_line
			(start 0.67945 0.3048)
			(end 0.120396 0.3048)
			(stroke
				(width 0.1)
				(type default)
			)
			(layer "F.Fab")
		)
		(pad "1" smd circle
			(at -0.40005 0)
			(size 0 0)
			(layers "F.Cu" "F.Mask" "F.Paste")
			(net "PVCCFA_EHV_CPU0")
		)
		(pad "2" smd circle
			(at 0.40005 0)
			(size 0 0)
			(layers "F.Cu" "F.Mask" "F.Paste")
			(net "GND")
		)
	)
	(footprint ""
		(layer "F.Cu")
		(at 430.600104 -131.599178 180)
		(property "Reference" "R2390"
			(at 0 0 180)
			(layer "F.SilkS")
			(hide yes)
			(effects
				(font
					(size 1.27 1.27)
				)
			)
		)
		(property "Value" ""
			(at 0 0 180)
			(layer "F.Fab")
			(effects
				(font
					(size 1.27 1.27)
				)
			)
		)
		(duplicate_pad_numbers_are_jumpers no)
		(fp_line
			(start 0.7874 0.4064)
			(end -0.7874 0.4064)
			(stroke
				(width 0.1524)
				(type default)
			)
			(layer "F.SilkS")
		)
		(fp_line
			(start 0.7874 -0.4064)
			(end 0.7874 0.4064)
			(stroke
				(width 0.1524)
				(type default)
			)
			(layer "F.SilkS")
		)
		(fp_line
			(start -0.7874 0.4064)
			(end -0.7874 -0.4064)
			(stroke
				(width 0.1524)
				(type default)
			)
			(layer "F.SilkS")
		)
		(fp_line
			(start -0.7874 -0.4064)
			(end 0.7874 -0.4064)
			(stroke
				(width 0.1524)
				(type default)
			)
			(layer "F.SilkS")
		)
		(fp_line
			(start 0.67945 0.3048)
			(end 0.120396 0.3048)
			(stroke
				(width 0.1)
				(type default)
			)
			(layer "F.Fab")
		)
		(fp_line
			(start 0.67945 -0.3048)
			(end 0.67945 0.3048)
			(stroke
				(width 0.1)
				(type default)
			)
			(layer "F.Fab")
		)
		(fp_line
			(start 0.12065 -0.2794)
			(end 0.12065 -0.3048)
			(stroke
				(width 0.1)
				(type default)
			)
			(layer "F.Fab")
		)
		(fp_line
			(start 0.12065 -0.3048)
			(end 0.67945 -0.3048)
			(stroke
				(width 0.1)
				(type default)
			)
			(layer "F.Fab")
		)
		(fp_line
			(start 0.120396 0.3048)
			(end 0.120396 0.2794)
			(stroke
				(width 0.1)
				(type default)
			)
			(layer "F.Fab")
		)
		(fp_line
			(start 0.120396 0.2794)
			(end -0.12065 0.2794)
			(stroke
				(width 0.1)
				(type default)
			)
			(layer "F.Fab")
		)
		(fp_line
			(start -0.12065 0.3048)
			(end -0.67945 0.3048)
			(stroke
				(width 0.1)
				(type default)
			)
			(layer "F.Fab")
		)
		(fp_line
			(start -0.12065 0.2794)
			(end -0.12065 0.3048)
			(stroke
				(width 0.1)
				(type default)
			)
			(layer "F.Fab")
		)
		(fp_line
			(start -0.12065 -0.2794)
			(end 0.12065 -0.2794)
			(stroke
				(width 0.1)
				(type default)
			)
			(layer "F.Fab")
		)
		(fp_line
			(start -0.12065 -0.305054)
			(end -0.12065 -0.2794)
			(stroke
				(width 0.1)
				(type default)
			)
			(layer "F.Fab")
		)
		(fp_line
			(start -0.67945 0.3048)
			(end -0.67945 -0.305054)
			(stroke
				(width 0.1)
				(type default)
			)
			(layer "F.Fab")
		)
		(fp_line
			(start -0.67945 -0.305054)
			(end -0.12065 -0.305054)
			(stroke
				(width 0.1)
				(type default)
			)
			(layer "F.Fab")
		)
		(pad "1" smd circle
			(at -0.40005 0 180)
			(size 0 0)
			(layers "F.Cu" "F.Mask" "F.Paste")
			(net "SMB_VR_3V3AUX_SCL_R2")
		)
		(pad "2" smd circle
			(at 0.40005 0 180)
			(size 0 0)
			(layers "F.Cu" "F.Mask" "F.Paste")
			(net "SMB_CLK_PVCCINFAON_CPU0")
		)
	)
)
